(kicad_pcb
	(version 20260206)
	(generator "pcbnew")
	(generator_version "10.0")
	(general
		(thickness 1.6)
		(legacy_teardrops no)
	)
	(paper "A4")
	(title_block
		(title "04192023_DAF0TMB3IC0_F0TG_MB_C_brd_V02_OCP.brd")
		(comment 1 "Grand Teton / footprints 5298-5304 of 8354")
	)
	(layers
		(0 "F.Cu" signal "TOP")
		(4 "In1.Cu" signal "GND")
		(6 "In2.Cu" signal "IN1")
		(8 "In3.Cu" signal "GND1")
		(10 "In4.Cu" signal "IN2")
		(12 "In5.Cu" signal "GND2")
		(14 "In6.Cu" signal "IN3")
		(16 "In7.Cu" signal "GND3")
		(18 "In8.Cu" signal "VCC")
		(20 "In9.Cu" signal "VCC1")
		(22 "In10.Cu" signal "GND4")
		(24 "In11.Cu" signal "IN4")
		(26 "In12.Cu" signal "GND5")
		(28 "In13.Cu" signal "IN5")
		(30 "In14.Cu" signal "GND6")
		(32 "In15.Cu" signal "IN6")
		(34 "In16.Cu" signal "GND7")
		(2 "B.Cu" signal "BOTTOM")
		(9 "F.Adhes" user "F.Adhesive")
		(11 "B.Adhes" user "B.Adhesive")
		(13 "F.Paste" user "Package Geometry/Pastemask Top")
		(15 "B.Paste" user "Package Geometry/Pastemask Bottom")
		(5 "F.SilkS" user "Ref Des/Silkscreen Top")
		(7 "B.SilkS" user "Ref Des/Silkscreen Bottom")
		(1 "F.Mask" user "Board Geometry/Soldermask Top")
		(3 "B.Mask" user "Board Geometry/Soldermask Bottom")
		(17 "Dwgs.User" user "User.Drawings")
		(19 "Cmts.User" user "User.Comments")
		(21 "Eco1.User" user "User.Eco1")
		(23 "Eco2.User" user "User.Eco2")
		(25 "Edge.Cuts" user "Board Geometry/Outline")
		(27 "Margin" user)
		(31 "F.CrtYd" user "Package Geometry/Place Bound Top")
		(29 "B.CrtYd" user "Package Geometry/Place Bound Bottom")
		(35 "F.Fab" user "Ref Des/Assembly Top")
		(33 "B.Fab" user "Ref Des/Assembly Bottom")
	)
	(footprint ""
		(layer "B.Cu")
		(at 84.595462 -181.684676 90)
		(property "Reference" "PR185"
			(at 0 0 90)
			(layer "B.SilkS")
			(hide yes)
			(effects
				(font
					(size 1.27 1.27)
				)
				(justify mirror)
			)
		)
		(property "Value" ""
			(at 0 0 90)
			(layer "B.Fab")
			(effects
				(font
					(size 1.27 1.27)
				)
				(justify mirror)
			)
		)
		(duplicate_pad_numbers_are_jumpers no)
		(fp_line
			(start 0.7874 -0.4064)
			(end -0.7874 -0.4064)
			(stroke
				(width 0.1524)
				(type default)
			)
			(layer "B.SilkS")
		)
		(fp_line
			(start -0.7874 -0.4064)
			(end -0.7874 0.4064)
			(stroke
				(width 0.1524)
				(type default)
			)
			(layer "B.SilkS")
		)
		(fp_line
			(start 0.7874 0.4064)
			(end 0.7874 -0.4064)
			(stroke
				(width 0.1524)
				(type default)
			)
			(layer "B.SilkS")
		)
		(fp_line
			(start -0.7874 0.4064)
			(end 0.7874 0.4064)
			(stroke
				(width 0.1524)
				(type default)
			)
			(layer "B.SilkS")
		)
		(fp_line
			(start 0.67945 -0.305054)
			(end 0.12065 -0.305054)
			(stroke
				(width 0.1)
				(type default)
			)
			(layer "B.Fab")
		)
		(fp_line
			(start 0.12065 -0.305054)
			(end 0.12065 -0.2794)
			(stroke
				(width 0.1)
				(type default)
			)
			(layer "B.Fab")
		)
		(fp_line
			(start -0.12065 -0.3048)
			(end -0.67945 -0.3048)
			(stroke
				(width 0.1)
				(type default)
			)
			(layer "B.Fab")
		)
		(fp_line
			(start -0.67945 -0.3048)
			(end -0.67945 0.3048)
			(stroke
				(width 0.1)
				(type default)
			)
			(layer "B.Fab")
		)
		(fp_line
			(start 0.12065 -0.2794)
			(end -0.12065 -0.2794)
			(stroke
				(width 0.1)
				(type default)
			)
			(layer "B.Fab")
		)
		(fp_line
			(start -0.12065 -0.2794)
			(end -0.12065 -0.3048)
			(stroke
				(width 0.1)
				(type default)
			)
			(layer "B.Fab")
		)
		(fp_line
			(start 0.12065 0.2794)
			(end 0.12065 0.3048)
			(stroke
				(width 0.1)
				(type default)
			)
			(layer "B.Fab")
		)
		(fp_line
			(start -0.120396 0.2794)
			(end 0.12065 0.2794)
			(stroke
				(width 0.1)
				(type default)
			)
			(layer "B.Fab")
		)
		(fp_line
			(start 0.67945 0.3048)
			(end 0.67945 -0.305054)
			(stroke
				(width 0.1)
				(type default)
			)
			(layer "B.Fab")
		)
		(fp_line
			(start 0.12065 0.3048)
			(end 0.67945 0.3048)
			(stroke
				(width 0.1)
				(type default)
			)
			(layer "B.Fab")
		)
		(fp_line
			(start -0.120396 0.3048)
			(end -0.120396 0.2794)
			(stroke
				(width 0.1)
				(type default)
			)
			(layer "B.Fab")
		)
		(fp_line
			(start -0.67945 0.3048)
			(end -0.120396 0.3048)
			(stroke
				(width 0.1)
				(type default)
			)
			(layer "B.Fab")
		)
		(pad "1" smd circle
			(at 0.40005 0 270)
			(size 0 0)
			(layers "B.Cu" "B.Mask" "B.Paste")
			(net "PVDDCR_CPU0_P1_PVCC")
		)
		(pad "2" smd circle
			(at -0.40005 0 270)
			(size 0 0)
			(layers "B.Cu" "B.Mask" "B.Paste")
			(net "PVDDCR_CPU0_P1_VCC1")
		)
	)
	(footprint ""
		(layer "B.Cu")
		(at 309.37835 -395.148562 90)
		(property "Reference" "C540"
			(at 0 0 90)
			(layer "B.SilkS")
			(hide yes)
			(effects
				(font
					(size 1.27 1.27)
				)
				(justify mirror)
			)
		)
		(property "Value" ""
			(at 0 0 90)
			(layer "B.Fab")
			(effects
				(font
					(size 1.27 1.27)
				)
				(justify mirror)
			)
		)
		(duplicate_pad_numbers_are_jumpers no)
		(fp_line
			(start 0.299974 -0.150114)
			(end -0.299974 -0.150114)
			(stroke
				(width 0.1)
				(type default)
			)
			(layer "B.Fab")
		)
		(fp_line
			(start -0.299974 -0.150114)
			(end -0.299974 0.150114)
			(stroke
				(width 0.1)
				(type default)
			)
			(layer "B.Fab")
		)
		(fp_line
			(start 0.299974 0.150114)
			(end 0.299974 -0.150114)
			(stroke
				(width 0.1)
				(type default)
			)
			(layer "B.Fab")
		)
		(fp_line
			(start -0.299974 0.150114)
			(end 0.299974 0.150114)
			(stroke
				(width 0.1)
				(type default)
			)
			(layer "B.Fab")
		)
		(pad "1" smd rect
			(at 0.2667 0 270)
			(size 0.3048 0.381)
			(layers "B.Cu" "B.Mask" "B.Paste")
			(net "P0V9_CPU0_RT_2D")
		)
		(pad "2" smd rect
			(at -0.2667 0 270)
			(size 0.3048 0.381)
			(layers "B.Cu" "B.Mask" "B.Paste")
			(net "GND")
		)
	)
	(footprint ""
		(layer "B.Cu")
		(at 109.49686 -35.088068 90)
		(property "Reference" "C6114"
			(at 0 0 90)
			(layer "B.SilkS")
			(hide yes)
			(effects
				(font
					(size 1.27 1.27)
				)
				(justify mirror)
			)
		)
		(property "Value" ""
			(at 0 0 90)
			(layer "B.Fab")
			(effects
				(font
					(size 1.27 1.27)
				)
				(justify mirror)
			)
		)
		(duplicate_pad_numbers_are_jumpers no)
		(fp_line
			(start 0.7874 -0.4064)
			(end -0.7874 -0.4064)
			(stroke
				(width 0.1524)
				(type default)
			)
			(layer "B.SilkS")
		)
		(fp_line
			(start -0.7874 -0.4064)
			(end -0.7874 0.4064)
			(stroke
				(width 0.1524)
				(type default)
			)
			(layer "B.SilkS")
		)
		(fp_line
			(start 0.7874 0.4064)
			(end 0.7874 -0.4064)
			(stroke
				(width 0.1524)
				(type default)
			)
			(layer "B.SilkS")
		)
		(fp_line
			(start -0.7874 0.4064)
			(end 0.7874 0.4064)
			(stroke
				(width 0.1524)
				(type default)
			)
			(layer "B.SilkS")
		)
		(fp_line
			(start 0.67945 -0.305054)
			(end 0.12065 -0.305054)
			(stroke
				(width 0.1)
				(type default)
			)
			(layer "B.Fab")
		)
		(fp_line
			(start 0.12065 -0.305054)
			(end 0.12065 -0.2794)
			(stroke
				(width 0.1)
				(type default)
			)
			(layer "B.Fab")
		)
		(fp_line
			(start -0.12065 -0.3048)
			(end -0.67945 -0.3048)
			(stroke
				(width 0.1)
				(type default)
			)
			(layer "B.Fab")
		)
		(fp_line
			(start -0.67945 -0.3048)
			(end -0.67945 0.3048)
			(stroke
				(width 0.1)
				(type default)
			)
			(layer "B.Fab")
		)
		(fp_line
			(start 0.12065 -0.2794)
			(end -0.12065 -0.2794)
			(stroke
				(width 0.1)
				(type default)
			)
			(layer "B.Fab")
		)
		(fp_line
			(start -0.12065 -0.2794)
			(end -0.12065 -0.3048)
			(stroke
				(width 0.1)
				(type default)
			)
			(layer "B.Fab")
		)
		(fp_line
			(start 0.12065 0.2794)
			(end 0.12065 0.3048)
			(stroke
				(width 0.1)
				(type default)
			)
			(layer "B.Fab")
		)
		(fp_line
			(start -0.120396 0.2794)
			(end 0.12065 0.2794)
			(stroke
				(width 0.1)
				(type default)
			)
			(layer "B.Fab")
		)
		(fp_line
			(start 0.67945 0.3048)
			(end 0.67945 -0.305054)
			(stroke
				(width 0.1)
				(type default)
			)
			(layer "B.Fab")
		)
		(fp_line
			(start 0.12065 0.3048)
			(end 0.67945 0.3048)
			(stroke
				(width 0.1)
				(type default)
			)
			(layer "B.Fab")
		)
		(fp_line
			(start -0.120396 0.3048)
			(end -0.120396 0.2794)
			(stroke
				(width 0.1)
				(type default)
			)
			(layer "B.Fab")
		)
		(fp_line
			(start -0.67945 0.3048)
			(end -0.120396 0.3048)
			(stroke
				(width 0.1)
				(type default)
			)
			(layer "B.Fab")
		)
		(pad "1" smd circle
			(at 0.40005 0 270)
			(size 0 0)
			(layers "B.Cu" "B.Mask" "B.Paste")
			(net "P1V2_CPU0_USB2_DVDD12")
		)
		(pad "2" smd circle
			(at -0.40005 0 270)
			(size 0 0)
			(layers "B.Cu" "B.Mask" "B.Paste")
			(net "GND")
		)
	)
	(footprint ""
		(layer "B.Cu")
		(at 208.461356 -382.596136)
		(property "Reference" "PR2513"
			(at 0 0 0)
			(layer "B.SilkS")
			(hide yes)
			(effects
				(font
					(size 1.27 1.27)
				)
				(justify mirror)
			)
		)
		(property "Value" ""
			(at 0 0 0)
			(layer "B.Fab")
			(effects
				(font
					(size 1.27 1.27)
				)
				(justify mirror)
			)
		)
		(duplicate_pad_numbers_are_jumpers no)
		(fp_line
			(start -0.7874 -0.4064)
			(end -0.7874 0.4064)
			(stroke
				(width 0.1524)
				(type default)
			)
			(layer "B.SilkS")
		)
		(fp_line
			(start -0.7874 0.4064)
			(end 0.7874 0.4064)
			(stroke
				(width 0.1524)
				(type default)
			)
			(layer "B.SilkS")
		)
		(fp_line
			(start 0.7874 -0.4064)
			(end -0.7874 -0.4064)
			(stroke
				(width 0.1524)
				(type default)
			)
			(layer "B.SilkS")
		)
		(fp_line
			(start 0.7874 0.4064)
			(end 0.7874 -0.4064)
			(stroke
				(width 0.1524)
				(type default)
			)
			(layer "B.SilkS")
		)
		(fp_line
			(start -0.67945 -0.3048)
			(end -0.67945 0.3048)
			(stroke
				(width 0.1)
				(type default)
			)
			(layer "B.Fab")
		)
		(fp_line
			(start -0.67945 0.3048)
			(end -0.120396 0.3048)
			(stroke
				(width 0.1)
				(type default)
			)
			(layer "B.Fab")
		)
		(fp_line
			(start -0.12065 -0.3048)
			(end -0.67945 -0.3048)
			(stroke
				(width 0.1)
				(type default)
			)
			(layer "B.Fab")
		)
		(fp_line
			(start -0.12065 -0.2794)
			(end -0.12065 -0.3048)
			(stroke
				(width 0.1)
				(type default)
			)
			(layer "B.Fab")
		)
		(fp_line
			(start -0.120396 0.2794)
			(end 0.12065 0.2794)
			(stroke
				(width 0.1)
				(type default)
			)
			(layer "B.Fab")
		)
		(fp_line
			(start -0.120396 0.3048)
			(end -0.120396 0.2794)
			(stroke
				(width 0.1)
				(type default)
			)
			(layer "B.Fab")
		)
		(fp_line
			(start 0.12065 -0.305054)
			(end 0.12065 -0.2794)
			(stroke
				(width 0.1)
				(type default)
			)
			(layer "B.Fab")
		)
		(fp_line
			(start 0.12065 -0.2794)
			(end -0.12065 -0.2794)
			(stroke
				(width 0.1)
				(type default)
			)
			(layer "B.Fab")
		)
		(fp_line
			(start 0.12065 0.2794)
			(end 0.12065 0.3048)
			(stroke
				(width 0.1)
				(type default)
			)
			(layer "B.Fab")
		)
		(fp_line
			(start 0.12065 0.3048)
			(end 0.67945 0.3048)
			(stroke
				(width 0.1)
				(type default)
			)
			(layer "B.Fab")
		)
		(fp_line
			(start 0.67945 -0.305054)
			(end 0.12065 -0.305054)
			(stroke
				(width 0.1)
				(type default)
			)
			(layer "B.Fab")
		)
		(fp_line
			(start 0.67945 0.3048)
			(end 0.67945 -0.305054)
			(stroke
				(width 0.1)
				(type default)
			)
			(layer "B.Fab")
		)
		(pad "1" smd circle
			(at 0.40005 0 180)
			(size 0 0)
			(layers "B.Cu" "B.Mask" "B.Paste")
			(net "P12V_HSC_ADC_P")
		)
		(pad "2" smd circle
			(at -0.40005 0 180)
			(size 0 0)
			(layers "B.Cu" "B.Mask" "B.Paste")
			(net "P12V_HSC_SENSE2_R4_P")
		)
	)
	(footprint ""
		(layer "B.Cu")
		(at 94.470474 -304.710592 180)
		(property "Reference" "R5031"
			(at 0 0 0)
			(layer "B.SilkS")
			(hide yes)
			(effects
				(font
					(size 1.27 1.27)
				)
				(justify mirror)
			)
		)
		(property "Value" ""
			(at 0 0 0)
			(layer "B.Fab")
			(effects
				(font
					(size 1.27 1.27)
				)
				(justify mirror)
			)
		)
		(duplicate_pad_numbers_are_jumpers no)
		(fp_line
			(start 0.7874 0.4064)
			(end 0.7874 -0.4064)
			(stroke
				(width 0.1524)
				(type default)
			)
			(layer "B.SilkS")
		)
		(fp_line
			(start 0.7874 -0.4064)
			(end -0.7874 -0.4064)
			(stroke
				(width 0.1524)
				(type default)
			)
			(layer "B.SilkS")
		)
		(fp_line
			(start -0.7874 0.4064)
			(end 0.7874 0.4064)
			(stroke
				(width 0.1524)
				(type default)
			)
			(layer "B.SilkS")
		)
		(fp_line
			(start -0.7874 -0.4064)
			(end -0.7874 0.4064)
			(stroke
				(width 0.1524)
				(type default)
			)
			(layer "B.SilkS")
		)
		(fp_line
			(start 0.67945 0.3048)
			(end 0.67945 -0.305054)
			(stroke
				(width 0.1)
				(type default)
			)
			(layer "B.Fab")
		)
		(fp_line
			(start 0.67945 -0.305054)
			(end 0.12065 -0.305054)
			(stroke
				(width 0.1)
				(type default)
			)
			(layer "B.Fab")
		)
		(fp_line
			(start 0.12065 0.3048)
			(end 0.67945 0.3048)
			(stroke
				(width 0.1)
				(type default)
			)
			(layer "B.Fab")
		)
		(fp_line
			(start 0.12065 0.2794)
			(end 0.12065 0.3048)
			(stroke
				(width 0.1)
				(type default)
			)
			(layer "B.Fab")
		)
		(fp_line
			(start 0.12065 -0.2794)
			(end -0.12065 -0.2794)
			(stroke
				(width 0.1)
				(type default)
			)
			(layer "B.Fab")
		)
		(fp_line
			(start 0.12065 -0.305054)
			(end 0.12065 -0.2794)
			(stroke
				(width 0.1)
				(type default)
			)
			(layer "B.Fab")
		)
		(fp_line
			(start -0.120396 0.3048)
			(end -0.120396 0.2794)
			(stroke
				(width 0.1)
				(type default)
			)
			(layer "B.Fab")
		)
		(fp_line
			(start -0.120396 0.2794)
			(end 0.12065 0.2794)
			(stroke
				(width 0.1)
				(type default)
			)
			(layer "B.Fab")
		)
		(fp_line
			(start -0.12065 -0.2794)
			(end -0.12065 -0.3048)
			(stroke
				(width 0.1)
				(type default)
			)
			(layer "B.Fab")
		)
		(fp_line
			(start -0.12065 -0.3048)
			(end -0.67945 -0.3048)
			(stroke
				(width 0.1)
				(type default)
			)
			(layer "B.Fab")
		)
		(fp_line
			(start -0.67945 0.3048)
			(end -0.120396 0.3048)
			(stroke
				(width 0.1)
				(type default)
			)
			(layer "B.Fab")
		)
		(fp_line
			(start -0.67945 -0.3048)
			(end -0.67945 0.3048)
			(stroke
				(width 0.1)
				(type default)
			)
			(layer "B.Fab")
		)
		(pad "1" smd circle
			(at 0.40005 0)
			(size 0 0)
			(layers "B.Cu" "B.Mask" "B.Paste")
			(net "GND")
		)
		(pad "2" smd circle
			(at -0.40005 0)
			(size 0 0)
			(layers "B.Cu" "B.Mask" "B.Paste")
			(net "FM_BMC_READY_N")
		)
	)
	(footprint ""
		(layer "B.Cu")
		(at 322.603876 -66.708782 90)
		(property "Reference" "R3086"
			(at 0 0 90)
			(layer "B.SilkS")
			(hide yes)
			(effects
				(font
					(size 1.27 1.27)
				)
				(justify mirror)
			)
		)
		(property "Value" ""
			(at 0 0 90)
			(layer "B.Fab")
			(effects
				(font
					(size 1.27 1.27)
				)
				(justify mirror)
			)
		)
		(duplicate_pad_numbers_are_jumpers no)
		(fp_line
			(start 0.7874 -0.4064)
			(end -0.7874 -0.4064)
			(stroke
				(width 0.1524)
				(type default)
			)
			(layer "B.SilkS")
		)
		(fp_line
			(start -0.7874 -0.4064)
			(end -0.7874 0.4064)
			(stroke
				(width 0.1524)
				(type default)
			)
			(layer "B.SilkS")
		)
		(fp_line
			(start 0.7874 0.4064)
			(end 0.7874 -0.4064)
			(stroke
				(width 0.1524)
				(type default)
			)
			(layer "B.SilkS")
		)
		(fp_line
			(start -0.7874 0.4064)
			(end 0.7874 0.4064)
			(stroke
				(width 0.1524)
				(type default)
			)
			(layer "B.SilkS")
		)
		(fp_line
			(start 0.67945 -0.305054)
			(end 0.12065 -0.305054)
			(stroke
				(width 0.1)
				(type default)
			)
			(layer "B.Fab")
		)
		(fp_line
			(start 0.12065 -0.305054)
			(end 0.12065 -0.2794)
			(stroke
				(width 0.1)
				(type default)
			)
			(layer "B.Fab")
		)
		(fp_line
			(start -0.12065 -0.3048)
			(end -0.67945 -0.3048)
			(stroke
				(width 0.1)
				(type default)
			)
			(layer "B.Fab")
		)
		(fp_line
			(start -0.67945 -0.3048)
			(end -0.67945 0.3048)
			(stroke
				(width 0.1)
				(type default)
			)
			(layer "B.Fab")
		)
		(fp_line
			(start 0.12065 -0.2794)
			(end -0.12065 -0.2794)
			(stroke
				(width 0.1)
				(type default)
			)
			(layer "B.Fab")
		)
		(fp_line
			(start -0.12065 -0.2794)
			(end -0.12065 -0.3048)
			(stroke
				(width 0.1)
				(type default)
			)
			(layer "B.Fab")
		)
		(fp_line
			(start 0.12065 0.2794)
			(end 0.12065 0.3048)
			(stroke
				(width 0.1)
				(type default)
			)
			(layer "B.Fab")
		)
		(fp_line
			(start -0.120396 0.2794)
			(end 0.12065 0.2794)
			(stroke
				(width 0.1)
				(type default)
			)
			(layer "B.Fab")
		)
		(fp_line
			(start 0.67945 0.3048)
			(end 0.67945 -0.305054)
			(stroke
				(width 0.1)
				(type default)
			)
			(layer "B.Fab")
		)
		(fp_line
			(start 0.12065 0.3048)
			(end 0.67945 0.3048)
			(stroke
				(width 0.1)
				(type default)
			)
			(layer "B.Fab")
		)
		(fp_line
			(start -0.120396 0.3048)
			(end -0.120396 0.2794)
			(stroke
				(width 0.1)
				(type default)
			)
			(layer "B.Fab")
		)
		(fp_line
			(start -0.67945 0.3048)
			(end -0.120396 0.3048)
			(stroke
				(width 0.1)
				(type default)
			)
			(layer "B.Fab")
		)
		(pad "1" smd circle
			(at 0.40005 0 270)
			(size 0 0)
			(layers "B.Cu" "B.Mask" "B.Paste")
			(net "LED_PWRGD_PVDD33_S5_R")
		)
		(pad "2" smd circle
			(at -0.40005 0 270)
			(size 0 0)
			(layers "B.Cu" "B.Mask" "B.Paste")
			(net "P3V3_AUX")
		)
	)
	(footprint ""
		(layer "B.Cu")
		(at 406.312878 -349.209614 -90)
		(property "Reference" "R6120"
			(at 0 0 90)
			(layer "B.SilkS")
			(hide yes)
			(effects
				(font
					(size 1.27 1.27)
				)
				(justify mirror)
			)
		)
		(property "Value" ""
			(at 0 0 90)
			(layer "B.Fab")
			(effects
				(font
					(size 1.27 1.27)
				)
				(justify mirror)
			)
		)
		(duplicate_pad_numbers_are_jumpers no)
		(fp_line
			(start -0.7874 0.4064)
			(end 0.7874 0.4064)
			(stroke
				(width 0.1524)
				(type default)
			)
			(layer "B.SilkS")
		)
		(fp_line
			(start 0.7874 0.4064)
			(end 0.7874 -0.4064)
			(stroke
				(width 0.1524)
				(type default)
			)
			(layer "B.SilkS")
		)
		(fp_line
			(start -0.7874 -0.4064)
			(end -0.7874 0.4064)
			(stroke
				(width 0.1524)
				(type default)
			)
			(layer "B.SilkS")
		)
		(fp_line
			(start 0.7874 -0.4064)
			(end -0.7874 -0.4064)
			(stroke
				(width 0.1524)
				(type default)
			)
			(layer "B.SilkS")
		)
		(fp_line
			(start -0.67945 0.3048)
			(end -0.120396 0.3048)
			(stroke
				(width 0.1)
				(type default)
			)
			(layer "B.Fab")
		)
		(fp_line
			(start -0.120396 0.3048)
			(end -0.120396 0.2794)
			(stroke
				(width 0.1)
				(type default)
			)
			(layer "B.Fab")
		)
		(fp_line
			(start 0.12065 0.3048)
			(end 0.67945 0.3048)
			(stroke
				(width 0.1)
				(type default)
			)
			(layer "B.Fab")
		)
		(fp_line
			(start 0.67945 0.3048)
			(end 0.67945 -0.305054)
			(stroke
				(width 0.1)
				(type default)
			)
			(layer "B.Fab")
		)
		(fp_line
			(start -0.120396 0.2794)
			(end 0.12065 0.2794)
			(stroke
				(width 0.1)
				(type default)
			)
			(layer "B.Fab")
		)
		(fp_line
			(start 0.12065 0.2794)
			(end 0.12065 0.3048)
			(stroke
				(width 0.1)
				(type default)
			)
			(layer "B.Fab")
		)
		(fp_line
			(start -0.12065 -0.2794)
			(end -0.12065 -0.3048)
			(stroke
				(width 0.1)
				(type default)
			)
			(layer "B.Fab")
		)
		(fp_line
			(start 0.12065 -0.2794)
			(end -0.12065 -0.2794)
			(stroke
				(width 0.1)
				(type default)
			)
			(layer "B.Fab")
		)
		(fp_line
			(start -0.67945 -0.3048)
			(end -0.67945 0.3048)
			(stroke
				(width 0.1)
				(type default)
			)
			(layer "B.Fab")
		)
		(fp_line
			(start -0.12065 -0.3048)
			(end -0.67945 -0.3048)
			(stroke
				(width 0.1)
				(type default)
			)
			(layer "B.Fab")
		)
		(fp_line
			(start 0.12065 -0.305054)
			(end 0.12065 -0.2794)
			(stroke
				(width 0.1)
				(type default)
			)
			(layer "B.Fab")
		)
		(fp_line
			(start 0.67945 -0.305054)
			(end 0.12065 -0.305054)
			(stroke
				(width 0.1)
				(type default)
			)
			(layer "B.Fab")
		)
		(pad "1" smd circle
			(at 0.40005 0 90)
			(size 0 0)
			(layers "B.Cu" "B.Mask" "B.Paste")
			(net "PVDD18_S5_P0")
		)
		(pad "2" smd circle
			(at -0.40005 0 90)
			(size 0 0)
			(layers "B.Cu" "B.Mask" "B.Paste")
			(net "FM_BOARD_SKU_ID4")
		)
	)
)
